(kicad_pcb
	(version 20241229)
	(generator "pcbnew")
	(generator_version "9.0")
	(general
		(thickness 1.61)
		(legacy_teardrops no)
	)
	(paper "A3")
	(title_block
		(title "RDIMM DDR5 Tester")
		(date "2026-05-21")
		(rev "2.2.0")
		(company "Antmicro")
		(comment 9 "footprints 508-512 of 796")
	)
	(layers
		(0 "F.Cu" signal)
		(4 "In1.Cu" power)
		(6 "In2.Cu" mixed)
		(8 "In3.Cu" power)
		(10 "In4.Cu" mixed)
		(12 "In5.Cu" power)
		(14 "In6.Cu" mixed)
		(16 "In7.Cu" power)
		(18 "In8.Cu" power)
		(20 "In9.Cu" mixed)
		(22 "In10.Cu" power)
		(2 "B.Cu" signal)
		(9 "F.Adhes" user "F.Adhesive")
		(11 "B.Adhes" user "B.Adhesive")
		(13 "F.Paste" user)
		(15 "B.Paste" user)
		(5 "F.SilkS" user "F.Silkscreen")
		(7 "B.SilkS" user "B.Silkscreen")
		(1 "F.Mask" user)
		(3 "B.Mask" user)
		(17 "Dwgs.User" user "User.Drawings")
		(19 "Cmts.User" user "User.Comments")
		(21 "Eco1.User" user "User.Eco1")
		(23 "Eco2.User" user "User.Eco2")
		(25 "Edge.Cuts" user)
		(27 "Margin" user)
		(31 "F.CrtYd" user "F.Courtyard")
		(29 "B.CrtYd" user "B.Courtyard")
		(35 "F.Fab" user)
		(33 "B.Fab" user)
	)
	(footprint "antmicro-footprints:R_0402_1005Metric"
		(layer "B.Cu")
		(at 254.324499 167.849 180)
		(descr "Resistor SMD 0402")
		(tags "resistor SMD 0402")
		(property "Reference" "R162"
			(at 0.9455 -0.304499 0)
			(layer "B.SilkS")
			(effects
				(font
					(size 0.7 0.7)
					(thickness 0.15)
				)
				(justify left bottom mirror)
			)
		)
		(property "Value" "R_0R_0402"
			(at -1.011843 -1.772047 0)
			(layer "B.Fab")
			(effects
				(font
					(size 0.7 0.7)
					(thickness 0.15)
				)
				(justify left bottom mirror)
			)
		)
		(property "Datasheet" "https://industrial.panasonic.com/cdbs/www-data/pdf/RDA0000/AOA0000C301.pdf"
			(at 0 0 180)
			(layer "F.Fab")
			(hide yes)
			(effects
				(font
					(size 1.27 1.27)
					(thickness 0.15)
				)
			)
		)
		(property "Manufacturer" "Panasonic"
			(at 0 0 180)
			(unlocked yes)
			(layer "B.Fab")
			(hide yes)
			(effects
				(font
					(size 1 1)
					(thickness 0.15)
				)
				(justify mirror)
			)
		)
		(property "MPN" "ERJ2GE0R00X"
			(at 0 0 180)
			(unlocked yes)
			(layer "B.Fab")
			(hide yes)
			(effects
				(font
					(size 1 1)
					(thickness 0.15)
				)
				(justify mirror)
			)
		)
		(property "Val" "0R"
			(at 0 0 180)
			(unlocked yes)
			(layer "B.Fab")
			(hide yes)
			(effects
				(font
					(size 1 1)
					(thickness 0.15)
				)
				(justify mirror)
			)
		)
		(property "License" "Apache-2.0"
			(at 0 0 180)
			(unlocked yes)
			(layer "B.Fab")
			(hide yes)
			(effects
				(font
					(size 1 1)
					(thickness 0.15)
				)
				(justify mirror)
			)
		)
		(property "Author" "Antmicro"
			(at 0 0 180)
			(unlocked yes)
			(layer "B.Fab")
			(hide yes)
			(effects
				(font
					(size 1 1)
					(thickness 0.15)
				)
				(justify mirror)
			)
		)
		(property "Tolerance" "~"
			(at 0 0 180)
			(unlocked yes)
			(layer "B.Fab")
			(hide yes)
			(effects
				(font
					(size 1 1)
					(thickness 0.15)
				)
				(justify mirror)
			)
		)
		(property "Current" "1A"
			(at 0 0 180)
			(unlocked yes)
			(layer "B.Fab")
			(hide yes)
			(effects
				(font
					(size 1 1)
					(thickness 0.15)
				)
				(justify mirror)
			)
		)
		(sheetname "/Supply/DC-DC AUX, MGT/")
		(sheetfile "dc-dc-aux-mgt.kicad_sch")
		(attr smd exclude_from_bom dnp)
		(fp_rect
			(start -0.925 0.47)
			(end 0.925 -0.47)
			(stroke
				(width 0.05)
				(type default)
			)
			(fill no)
			(layer "B.CrtYd")
		)
		(fp_rect
			(start -0.5 0.25)
			(end 0.5 -0.25)
			(stroke
				(width 0.15)
				(type solid)
			)
			(fill no)
			(layer "B.Fab")
		)
		(fp_text user "${REFERENCE}"
			(at -0.95 -3.168 0)
			(layer "B.Fab")
			(effects
				(font
					(size 0.7 0.7)
					(thickness 0.15)
				)
				(justify left bottom mirror)
			)
		)
		(fp_text user "License: Apache-2.0"
			(at -0.95 -5.169 0)
			(layer "B.Fab")
			(effects
				(font
					(size 0.7 0.7)
					(thickness 0.15)
				)
				(justify left bottom mirror)
			)
		)
		(fp_text user "Author: Antmicro"
			(at -0.95 -4.169 0)
			(layer "B.Fab")
			(effects
				(font
					(size 0.7 0.7)
					(thickness 0.15)
				)
				(justify left bottom mirror)
			)
		)
		(pad "1" smd roundrect
			(at -0.48 0 180)
			(size 0.59 0.64)
			(layers "B.Cu" "B.Mask" "B.Paste")
			(roundrect_rratio 0.25)
			(net 1 "GND")
			(pintype "passive")
		)
		(pad "2" smd roundrect
			(at 0.48 0 180)
			(size 0.59 0.64)
			(layers "B.Cu" "B.Mask" "B.Paste")
			(roundrect_rratio 0.25)
			(net 713 "/Supply/DC-DC AUX, MGT/FB2")
			(pintype "passive")
		)
	)
	(footprint "antmicro-footprints:C_0402_1005Metric_EIA"
		(layer "B.Cu")
		(at 185 150.5 -90)
		(descr "Capacitor SMD 0402 (1005 Metric), square (rectangular) end terminal, IPC_7351 nominal, (Body size source: IPC-SM-782 page 76, https://www.pcb-3d.com/wordpress/wp-content/uploads/ipc-sm-782a_amendment_1_and_2.pdf)")
		(tags "capacitor 0402")
		(property "Reference" "C36"
			(at -11.525 30.625 90)
			(layer "B.SilkS")
			(effects
				(font
					(size 0.7 0.7)
					(thickness 0.15)
				)
				(justify left bottom mirror)
			)
		)
		(property "Value" "C_1u_25V_0402"
			(at 0 -1.169 90)
			(layer "B.Fab")
			(effects
				(font
					(size 0.7 0.7)
					(thickness 0.15)
				)
				(justify left bottom mirror)
			)
		)
		(property "Datasheet" "https://www.murata.com/products/productdetail?partno=GRM155R61E105KE11%23"
			(at 0 0 270)
			(layer "F.Fab")
			(hide yes)
			(effects
				(font
					(size 1.27 1.27)
					(thickness 0.15)
				)
			)
		)
		(property "MPN" "GRM155R61E105KE11J"
			(at 0 0 270)
			(unlocked yes)
			(layer "B.Fab")
			(hide yes)
			(effects
				(font
					(size 1 1)
					(thickness 0.15)
				)
				(justify mirror)
			)
		)
		(property "Manufacturer" "Murata"
			(at 0 0 270)
			(unlocked yes)
			(layer "B.Fab")
			(hide yes)
			(effects
				(font
					(size 1 1)
					(thickness 0.15)
				)
				(justify mirror)
			)
		)
		(property "License" "Apache-2.0"
			(at 0 0 270)
			(unlocked yes)
			(layer "B.Fab")
			(hide yes)
			(effects
				(font
					(size 1 1)
					(thickness 0.15)
				)
				(justify mirror)
			)
		)
		(property "Author" "Antmicro"
			(at 0 0 270)
			(unlocked yes)
			(layer "B.Fab")
			(hide yes)
			(effects
				(font
					(size 1 1)
					(thickness 0.15)
				)
				(justify mirror)
			)
		)
		(property "Val" "1u"
			(at 0 0 270)
			(unlocked yes)
			(layer "B.Fab")
			(hide yes)
			(effects
				(font
					(size 1 1)
					(thickness 0.15)
				)
				(justify mirror)
			)
		)
		(property "Voltage" "25V"
			(at 0 0 270)
			(unlocked yes)
			(layer "B.Fab")
			(hide yes)
			(effects
				(font
					(size 1 1)
					(thickness 0.15)
				)
				(justify mirror)
			)
		)
		(property "Dielectric" "X5R"
			(at 0 0 270)
			(unlocked yes)
			(layer "B.Fab")
			(hide yes)
			(effects
				(font
					(size 1 1)
					(thickness 0.15)
				)
				(justify mirror)
			)
		)
		(sheetname "/FPGA power/")
		(sheetfile "fpga-power.kicad_sch")
		(attr smd)
		(fp_rect
			(start -0.95 0.45)
			(end 0.95 -0.45)
			(stroke
				(width 0.05)
				(type default)
			)
			(fill no)
			(layer "B.CrtYd")
		)
		(fp_line
			(start -0.5 0.25)
			(end 0.498 0.25)
			(stroke
				(width 0.15)
				(type solid)
			)
			(layer "B.Fab")
		)
		(fp_line
			(start 0.498 0.25)
			(end 0.498 -0.248)
			(stroke
				(width 0.15)
				(type solid)
			)
			(layer "B.Fab")
		)
		(fp_line
			(start -0.5 -0.248)
			(end -0.5 0.25)
			(stroke
				(width 0.15)
				(type solid)
			)
			(layer "B.Fab")
		)
		(fp_line
			(start 0.498 -0.248)
			(end -0.5 -0.248)
			(stroke
				(width 0.15)
				(type solid)
			)
			(layer "B.Fab")
		)
		(fp_text user "License: Apache-2.0"
			(at -0.9656 -4.369 90)
			(layer "B.Fab")
			(effects
				(font
					(size 0.7 0.7)
					(thickness 0.15)
				)
				(justify left bottom mirror)
			)
		)
		(fp_text user "${REFERENCE}"
			(at -0.9656 -3.169 90)
			(layer "B.Fab")
			(effects
				(font
					(size 0.7 0.7)
					(thickness 0.15)
				)
				(justify left bottom mirror)
			)
		)
		(fp_text user "Author: Antmicro"
			(at -0.9656 -5.569 90)
			(layer "B.Fab")
			(effects
				(font
					(size 0.7 0.7)
					(thickness 0.15)
				)
				(justify left bottom mirror)
			)
		)
		(pad "1" smd roundrect
			(at -0.5 0 180)
			(size 0.6 0.6)
			(layers "B.Cu" "B.Mask" "B.Paste")
			(roundrect_rratio 0.25)
			(net 1 "GND")
			(pintype "passive")
		)
		(pad "2" smd roundrect
			(at 0.498 0 270)
			(size 0.6 0.6)
			(layers "B.Cu" "B.Mask" "B.Paste")
			(roundrect_rratio 0.25)
			(net 553 "+0V85")
			(pintype "passive")
		)
	)
	(footprint "antmicro-footprints:R_0402_1005Metric"
		(layer "B.Cu")
		(at 254.365 177.6)
		(descr "Resistor SMD 0402")
		(tags "resistor SMD 0402")
		(property "Reference" "R153"
			(at 0.935 0.45 0)
			(layer "B.SilkS")
			(effects
				(font
					(size 0.7 0.7)
					(thickness 0.15)
				)
				(justify right bottom mirror)
			)
		)
		(property "Value" "R_0R_0402"
			(at -1.011843 -1.772047 0)
			(layer "B.Fab")
			(effects
				(font
					(size 0.7 0.7)
					(thickness 0.15)
				)
				(justify right bottom mirror)
			)
		)
		(property "Datasheet" "https://industrial.panasonic.com/cdbs/www-data/pdf/RDA0000/AOA0000C301.pdf"
			(at 0 0 0)
			(layer "F.Fab")
			(hide yes)
			(effects
				(font
					(size 1.27 1.27)
					(thickness 0.15)
				)
			)
		)
		(property "Manufacturer" "Panasonic"
			(at 0 0 0)
			(unlocked yes)
			(layer "B.Fab")
			(hide yes)
			(effects
				(font
					(size 1 1)
					(thickness 0.15)
				)
				(justify mirror)
			)
		)
		(property "MPN" "ERJ2GE0R00X"
			(at 0 0 0)
			(unlocked yes)
			(layer "B.Fab")
			(hide yes)
			(effects
				(font
					(size 1 1)
					(thickness 0.15)
				)
				(justify mirror)
			)
		)
		(property "Val" "0R"
			(at 0 0 0)
			(unlocked yes)
			(layer "B.Fab")
			(hide yes)
			(effects
				(font
					(size 1 1)
					(thickness 0.15)
				)
				(justify mirror)
			)
		)
		(property "License" "Apache-2.0"
			(at 0 0 0)
			(unlocked yes)
			(layer "B.Fab")
			(hide yes)
			(effects
				(font
					(size 1 1)
					(thickness 0.15)
				)
				(justify mirror)
			)
		)
		(property "Author" "Antmicro"
			(at 0 0 0)
			(unlocked yes)
			(layer "B.Fab")
			(hide yes)
			(effects
				(font
					(size 1 1)
					(thickness 0.15)
				)
				(justify mirror)
			)
		)
		(property "Tolerance" "~"
			(at 0 0 0)
			(unlocked yes)
			(layer "B.Fab")
			(hide yes)
			(effects
				(font
					(size 1 1)
					(thickness 0.15)
				)
				(justify mirror)
			)
		)
		(property "Current" "1A"
			(at 0 0 0)
			(unlocked yes)
			(layer "B.Fab")
			(hide yes)
			(effects
				(font
					(size 1 1)
					(thickness 0.15)
				)
				(justify mirror)
			)
		)
		(sheetname "/Supply/DC-DC AUX, MGT/")
		(sheetfile "dc-dc-aux-mgt.kicad_sch")
		(attr smd exclude_from_bom dnp)
		(fp_rect
			(start -0.925 0.47)
			(end 0.925 -0.47)
			(stroke
				(width 0.05)
				(type default)
			)
			(fill no)
			(layer "B.CrtYd")
		)
		(fp_rect
			(start -0.5 0.25)
			(end 0.5 -0.25)
			(stroke
				(width 0.15)
				(type solid)
			)
			(fill no)
			(layer "B.Fab")
		)
		(fp_text user "Author: Antmicro"
			(at -0.95 -4.169 180)
			(layer "B.Fab")
			(effects
				(font
					(size 0.7 0.7)
					(thickness 0.15)
				)
				(justify left bottom mirror)
			)
		)
		(fp_text user "${REFERENCE}"
			(at -0.95 -3.168 180)
			(layer "B.Fab")
			(effects
				(font
					(size 0.7 0.7)
					(thickness 0.15)
				)
				(justify left bottom mirror)
			)
		)
		(fp_text user "License: Apache-2.0"
			(at -0.95 -5.169 180)
			(layer "B.Fab")
			(effects
				(font
					(size 0.7 0.7)
					(thickness 0.15)
				)
				(justify left bottom mirror)
			)
		)
		(pad "1" smd roundrect
			(at -0.48 0)
			(size 0.59 0.64)
			(layers "B.Cu" "B.Mask" "B.Paste")
			(roundrect_rratio 0.25)
			(net 1 "GND")
			(pintype "passive")
		)
		(pad "2" smd roundrect
			(at 0.48 0)
			(size 0.59 0.64)
			(layers "B.Cu" "B.Mask" "B.Paste")
			(roundrect_rratio 0.25)
			(net 712 "/Supply/DC-DC AUX, MGT/FB1")
			(pintype "passive")
		)
	)
	(footprint "antmicro-footprints:C_0402_1005Metric_EIA"
		(layer "B.Cu")
		(at 197 148.5 90)
		(descr "Capacitor SMD 0402 (1005 Metric), square (rectangular) end terminal, IPC_7351 nominal, (Body size source: IPC-SM-782 page 76, https://www.pcb-3d.com/wordpress/wp-content/uploads/ipc-sm-782a_amendment_1_and_2.pdf)")
		(tags "capacitor 0402")
		(property "Reference" "C20"
			(at -3.15 0.45 90)
			(layer "B.SilkS")
			(effects
				(font
					(size 0.7 0.7)
					(thickness 0.15)
				)
				(justify right bottom mirror)
			)
		)
		(property "Value" "C_100n_0402"
			(at 0 -1.169 90)
			(layer "B.Fab")
			(effects
				(font
					(size 0.7 0.7)
					(thickness 0.15)
				)
				(justify right bottom mirror)
			)
		)
		(property "Datasheet" "https://www.murata.com/products/productdetail?partno=GRM155R61H104KE14%23"
			(at 0 0 90)
			(layer "F.Fab")
			(hide yes)
			(effects
				(font
					(size 1.27 1.27)
					(thickness 0.15)
				)
			)
		)
		(property "MPN" "GRM155R61H104KE14D"
			(at 0 0 90)
			(unlocked yes)
			(layer "B.Fab")
			(hide yes)
			(effects
				(font
					(size 1 1)
					(thickness 0.15)
				)
				(justify mirror)
			)
		)
		(property "Manufacturer" "Murata"
			(at 0 0 90)
			(unlocked yes)
			(layer "B.Fab")
			(hide yes)
			(effects
				(font
					(size 1 1)
					(thickness 0.15)
				)
				(justify mirror)
			)
		)
		(property "License" "Apache-2.0"
			(at 0 0 90)
			(unlocked yes)
			(layer "B.Fab")
			(hide yes)
			(effects
				(font
					(size 1 1)
					(thickness 0.15)
				)
				(justify mirror)
			)
		)
		(property "Author" "Antmicro"
			(at 0 0 90)
			(unlocked yes)
			(layer "B.Fab")
			(hide yes)
			(effects
				(font
					(size 1 1)
					(thickness 0.15)
				)
				(justify mirror)
			)
		)
		(property "Val" "100n"
			(at 0 0 90)
			(unlocked yes)
			(layer "B.Fab")
			(hide yes)
			(effects
				(font
					(size 1 1)
					(thickness 0.15)
				)
				(justify mirror)
			)
		)
		(property "Voltage" "50V"
			(at 0 0 90)
			(unlocked yes)
			(layer "B.Fab")
			(hide yes)
			(effects
				(font
					(size 1 1)
					(thickness 0.15)
				)
				(justify mirror)
			)
		)
		(property "Dielectric" "X5R"
			(at 0 0 90)
			(unlocked yes)
			(layer "B.Fab")
			(hide yes)
			(effects
				(font
					(size 1 1)
					(thickness 0.15)
				)
				(justify mirror)
			)
		)
		(sheetname "/FPGA power/")
		(sheetfile "fpga-power.kicad_sch")
		(attr smd)
		(fp_rect
			(start -0.95 0.45)
			(end 0.95 -0.45)
			(stroke
				(width 0.05)
				(type default)
			)
			(fill no)
			(layer "B.CrtYd")
		)
		(fp_line
			(start 0.498 -0.248)
			(end -0.5 -0.248)
			(stroke
				(width 0.15)
				(type solid)
			)
			(layer "B.Fab")
		)
		(fp_line
			(start -0.5 -0.248)
			(end -0.5 0.25)
			(stroke
				(width 0.15)
				(type solid)
			)
			(layer "B.Fab")
		)
		(fp_line
			(start 0.498 0.25)
			(end 0.498 -0.248)
			(stroke
				(width 0.15)
				(type solid)
			)
			(layer "B.Fab")
		)
		(fp_line
			(start -0.5 0.25)
			(end 0.498 0.25)
			(stroke
				(width 0.15)
				(type solid)
			)
			(layer "B.Fab")
		)
		(fp_text user "${REFERENCE}"
			(at -0.9656 -3.169 270)
			(layer "B.Fab")
			(effects
				(font
					(size 0.7 0.7)
					(thickness 0.15)
				)
				(justify left bottom mirror)
			)
		)
		(fp_text user "License: Apache-2.0"
			(at -0.9656 -4.369 270)
			(layer "B.Fab")
			(effects
				(font
					(size 0.7 0.7)
					(thickness 0.15)
				)
				(justify left bottom mirror)
			)
		)
		(fp_text user "Author: Antmicro"
			(at -0.9656 -5.569 270)
			(layer "B.Fab")
			(effects
				(font
					(size 0.7 0.7)
					(thickness 0.15)
				)
				(justify left bottom mirror)
			)
		)
		(pad "1" smd roundrect
			(at -0.5 0)
			(size 0.6 0.6)
			(layers "B.Cu" "B.Mask" "B.Paste")
			(roundrect_rratio 0.25)
			(net 1 "GND")
			(pintype "passive")
		)
		(pad "2" smd roundrect
			(at 0.498 0 90)
			(size 0.6 0.6)
			(layers "B.Cu" "B.Mask" "B.Paste")
			(roundrect_rratio 0.25)
			(net 687 "VDDQ")
			(pintype "passive")
		)
	)
	(footprint "antmicro-footprints:C_0402_1005Metric"
		(layer "B.Cu")
		(at 176.65 193.249501 90)
		(descr "Capacitor SMD 0402")
		(tags "capacitor SMD 0402")
		(property "Reference" "C230"
			(at 0.994 0.403501 90)
			(layer "B.SilkS")
			(effects
				(font
					(size 0.7 0.7)
					(thickness 0.15)
				)
				(justify right bottom mirror)
			)
		)
		(property "Value" "C_100n_0402"
			(at -1.022927 -2.155213 90)
			(layer "B.Fab")
			(effects
				(font
					(size 0.7 0.7)
					(thickness 0.15)
				)
				(justify right bottom mirror)
			)
		)
		(property "Datasheet" "https://www.murata.com/products/productdetail?partno=GRM155R61H104KE14%23"
			(at 0 0 90)
			(layer "F.Fab")
			(hide yes)
			(effects
				(font
					(size 1.27 1.27)
					(thickness 0.15)
				)
			)
		)
		(property "Manufacturer" "Murata"
			(at 0 0 90)
			(unlocked yes)
			(layer "B.Fab")
			(hide yes)
			(effects
				(font
					(size 1 1)
					(thickness 0.15)
				)
				(justify mirror)
			)
		)
		(property "MPN" "GRM155R61H104KE14D"
			(at 0 0 90)
			(unlocked yes)
			(layer "B.Fab")
			(hide yes)
			(effects
				(font
					(size 1 1)
					(thickness 0.15)
				)
				(justify mirror)
			)
		)
		(property "Val" "100n"
			(at 0 0 90)
			(unlocked yes)
			(layer "B.Fab")
			(hide yes)
			(effects
				(font
					(size 1 1)
					(thickness 0.15)
				)
				(justify mirror)
			)
		)
		(property "License" "Apache-2.0"
			(at 0 0 90)
			(unlocked yes)
			(layer "B.Fab")
			(hide yes)
			(effects
				(font
					(size 1 1)
					(thickness 0.15)
				)
				(justify mirror)
			)
		)
		(property "Author" "Antmicro"
			(at 0 0 90)
			(unlocked yes)
			(layer "B.Fab")
			(hide yes)
			(effects
				(font
					(size 1 1)
					(thickness 0.15)
				)
				(justify mirror)
			)
		)
		(property "Voltage" "50V"
			(at 0 0 90)
			(unlocked yes)
			(layer "B.Fab")
			(hide yes)
			(effects
				(font
					(size 1 1)
					(thickness 0.15)
				)
				(justify mirror)
			)
		)
		(property "Dielectric" "X5R"
			(at 0 0 90)
			(unlocked yes)
			(layer "B.Fab")
			(hide yes)
			(effects
				(font
					(size 1 1)
					(thickness 0.15)
				)
				(justify mirror)
			)
		)
		(sheetname "/FPGA MGT Interface/")
		(sheetfile "fpga-mgt.kicad_sch")
		(attr smd)
		(fp_rect
			(start -0.925 0.47)
			(end 0.925 -0.47)
			(stroke
				(width 0.05)
				(type default)
			)
			(fill no)
			(layer "B.CrtYd")
		)
		(fp_line
			(start 0.504 -0.248)
			(end -0.494 -0.248)
			(stroke
				(width 0.15)
				(type solid)
			)
			(layer "B.Fab")
		)
		(fp_line
			(start -0.494 -0.248)
			(end -0.494 0.25)
			(stroke
				(width 0.15)
				(type solid)
			)
			(layer "B.Fab")
		)
		(fp_line
			(start 0.504 0.25)
			(end 0.504 -0.248)
			(stroke
				(width 0.15)
				(type solid)
			)
			(layer "B.Fab")
		)
		(fp_line
			(start -0.494 0.25)
			(end 0.504 0.25)
			(stroke
				(width 0.15)
				(type solid)
			)
			(layer "B.Fab")
		)
		(fp_text user "${REFERENCE}"
			(at -0.939 -4.599 270)
			(layer "B.Fab")
			(effects
				(font
					(size 0.7 0.7)
					(thickness 0.15)
				)
				(justify left bottom mirror)
			)
		)
		(fp_text user "License: Apache-2.0"
			(at -0.939 -5.799 270)
			(layer "B.Fab")
			(effects
				(font
					(size 0.7 0.7)
					(thickness 0.15)
				)
				(justify left bottom mirror)
			)
		)
		(fp_text user "Author: Antmicro"
			(at -0.939 -3.399 270)
			(layer "B.Fab")
			(effects
				(font
					(size 0.7 0.7)
					(thickness 0.15)
				)
				(justify left bottom mirror)
			)
		)
		(pad "1" smd roundrect
			(at -0.48 0 90)
			(size 0.59 0.64)
			(layers "B.Cu" "B.Mask" "B.Paste")
			(roundrect_rratio 0.25)
			(net 23 "/FPGA MGT Interface/PCIE.TXD3_N")
			(pintype "passive")
		)
		(pad "2" smd roundrect
			(at 0.48 0 90)
			(size 0.59 0.64)
			(layers "B.Cu" "B.Mask" "B.Paste")
			(roundrect_rratio 0.25)
			(net 24 "/FPGA MGT Interface/GTY_225_TX0_N")
			(pintype "passive")
		)
	)
)
